(kicad_pcb
	(version 20260206)
	(generator "pcbnew")
	(generator_version "10.0")
	(general
		(thickness 1.6)
		(legacy_teardrops no)
	)
	(paper "A4")
	(title_block
		(title "panther-plus-userver — 13130-1b_20150205.brd")
		(comment 1 "Honey Badger (Wiwynn) / footprints 207-214 of 1509")
	)
	(layers
		(0 "F.Cu" signal "TOP")
		(4 "In1.Cu" signal "L2")
		(6 "In2.Cu" signal "L3")
		(8 "In3.Cu" signal "L4")
		(10 "In4.Cu" signal "L5")
		(12 "In5.Cu" signal "L6")
		(14 "In6.Cu" signal "L7")
		(16 "In7.Cu" signal "L8")
		(18 "In8.Cu" signal "L9")
		(20 "In9.Cu" signal "L10")
		(22 "In10.Cu" signal "L11")
		(2 "B.Cu" signal "BOTTOM")
		(9 "F.Adhes" user "F.Adhesive")
		(11 "B.Adhes" user "B.Adhesive")
		(13 "F.Paste" user "Package Geometry/Pastemask Top")
		(15 "B.Paste" user "Package Geometry/Pastemask Bottom")
		(5 "F.SilkS" user "Ref Des/Silkscreen Top")
		(7 "B.SilkS" user "Ref Des/Silkscreen Bottom")
		(1 "F.Mask" user "Board Geometry/Soldermask Top")
		(3 "B.Mask" user "Board Geometry/Soldermask Bottom")
		(17 "Dwgs.User" user "User.Drawings")
		(19 "Cmts.User" user "User.Comments")
		(21 "Eco1.User" user "User.Eco1")
		(23 "Eco2.User" user "User.Eco2")
		(25 "Edge.Cuts" user "Board Geometry/Outline")
		(27 "Margin" user)
		(31 "F.CrtYd" user "Package Geometry/Place Bound Top")
		(29 "B.CrtYd" user "Package Geometry/Place Bound Bottom")
		(35 "F.Fab" user "Ref Des/Assembly Top")
		(33 "B.Fab" user "Ref Des/Assembly Bottom")
	)
	(footprint ""
		(layer "F.Cu")
		(at 118.237 -36.084002 180)
		(property "Reference" "PR117"
			(at 0 0 180)
			(layer "F.SilkS")
			(hide yes)
			(effects
				(font
					(size 1.27 1.27)
				)
			)
		)
		(property "Value" "10R2F-L-GP"
			(at 0.064008 -3.993896 180)
			(unlocked yes)
			(layer "F.Fab")
			(hide yes)
			(effects
				(font
					(size 1.016 1.016)
					(thickness 0.1524)
				)
			)
		)
		(property "Device Type" "R402H14"
			(at 0.064008 -5.517896 180)
			(unlocked yes)
			(layer "F.Fab")
			(hide yes)
			(effects
				(font
					(size 1.016 1.016)
					(thickness 0.1524)
				)
			)
		)
		(duplicate_pad_numbers_are_jumpers no)
		(fp_rect
			(start -0.381 0.8382)
			(end 0.381 -0.8382)
			(stroke
				(width 0)
				(type default)
			)
			(fill no)
			(layer "F.CrtYd")
		)
		(fp_rect
			(start -0.381 0.8382)
			(end 0.381 -0.8382)
			(stroke
				(width 0)
				(type default)
			)
			(fill no)
			(layer "F.Fab")
		)
		(pad "1" smd custom
			(at 0 -0.4318 180)
			(size 0.127 0.127)
			(layers "F.Cu" "F.Mask" "F.Paste")
			(net "PVCCP")
			(options
				(clearance outline)
				(anchor circle)
			)
			(primitives
				(gr_poly
					(pts
						(arc
							(start -0.2032 -0.2794)
							(mid -0.239121 -0.264521)
							(end -0.254 -0.2286)
						)
						(arc
							(start -0.254 0.2286)
							(mid -0.239121 0.264521)
							(end -0.2032 0.2794)
						)
						(arc
							(start 0.2032 0.2794)
							(mid 0.239121 0.264521)
							(end 0.254 0.2286)
						)
						(arc
							(start 0.254 -0.2286)
							(mid 0.239121 -0.264521)
							(end 0.2032 -0.2794)
						)
					)
					(width 0)
					(fill yes)
				)
			)
		)
		(pad "2" smd custom
			(at 0 0.4318 180)
			(size 0.127 0.127)
			(layers "F.Cu" "F.Mask" "F.Paste")
			(net "VR_PVCCP_VSEN")
			(options
				(clearance outline)
				(anchor circle)
			)
			(primitives
				(gr_poly
					(pts
						(arc
							(start -0.2032 -0.2794)
							(mid -0.239121 -0.264521)
							(end -0.254 -0.2286)
						)
						(arc
							(start -0.254 0.2286)
							(mid -0.239121 0.264521)
							(end -0.2032 0.2794)
						)
						(arc
							(start 0.2032 0.2794)
							(mid 0.239121 0.264521)
							(end 0.254 0.2286)
						)
						(arc
							(start 0.254 -0.2286)
							(mid 0.239121 -0.264521)
							(end 0.2032 -0.2794)
						)
					)
					(width 0)
					(fill yes)
				)
			)
		)
	)
	(footprint ""
		(layer "F.Cu")
		(at 161.036 -35.052 180)
		(property "Reference" "R164"
			(at 0 0 180)
			(layer "F.SilkS")
			(hide yes)
			(effects
				(font
					(size 1.27 1.27)
				)
			)
		)
		(property "Value" "10KR2F-2-GP"
			(at 0.064008 -3.993896 180)
			(unlocked yes)
			(layer "F.Fab")
			(hide yes)
			(effects
				(font
					(size 1.016 1.016)
					(thickness 0.1524)
				)
			)
		)
		(property "Device Type" "R402H16"
			(at 0.064008 -5.517896 180)
			(unlocked yes)
			(layer "F.Fab")
			(hide yes)
			(effects
				(font
					(size 1.016 1.016)
					(thickness 0.1524)
				)
			)
		)
		(duplicate_pad_numbers_are_jumpers no)
		(fp_rect
			(start -0.381 0.8382)
			(end 0.381 -0.8382)
			(stroke
				(width 0)
				(type default)
			)
			(fill no)
			(layer "F.CrtYd")
		)
		(fp_rect
			(start -0.381 0.8382)
			(end 0.381 -0.8382)
			(stroke
				(width 0)
				(type default)
			)
			(fill no)
			(layer "F.Fab")
		)
		(pad "1" smd custom
			(at 0 -0.4318 180)
			(size 0.127 0.127)
			(layers "F.Cu" "F.Mask" "F.Paste")
			(net "DISABLE")
			(options
				(clearance outline)
				(anchor circle)
			)
			(primitives
				(gr_poly
					(pts
						(arc
							(start -0.2032 -0.2794)
							(mid -0.239121 -0.264521)
							(end -0.254 -0.2286)
						)
						(arc
							(start -0.254 0.2286)
							(mid -0.239121 0.264521)
							(end -0.2032 0.2794)
						)
						(arc
							(start 0.2032 0.2794)
							(mid 0.239121 0.264521)
							(end 0.254 0.2286)
						)
						(arc
							(start 0.254 -0.2286)
							(mid 0.239121 -0.264521)
							(end 0.2032 -0.2794)
						)
					)
					(width 0)
					(fill yes)
				)
			)
		)
		(pad "2" smd custom
			(at 0 0.4318 180)
			(size 0.127 0.127)
			(layers "F.Cu" "F.Mask" "F.Paste")
			(net "GND")
			(options
				(clearance outline)
				(anchor circle)
			)
			(primitives
				(gr_poly
					(pts
						(arc
							(start -0.2032 -0.2794)
							(mid -0.239121 -0.264521)
							(end -0.254 -0.2286)
						)
						(arc
							(start -0.254 0.2286)
							(mid -0.239121 0.264521)
							(end -0.2032 0.2794)
						)
						(arc
							(start 0.2032 0.2794)
							(mid 0.239121 0.264521)
							(end 0.254 0.2286)
						)
						(arc
							(start 0.254 -0.2286)
							(mid 0.239121 -0.264521)
							(end 0.2032 -0.2794)
						)
					)
					(width 0)
					(fill yes)
				)
			)
		)
	)
	(footprint ""
		(layer "F.Cu")
		(at 86.106 -15.113)
		(property "Reference" "PC199"
			(at 0 0 0)
			(layer "F.SilkS")
			(hide yes)
			(effects
				(font
					(size 1.27 1.27)
				)
			)
		)
		(property "Value" "SC10U6D3V5KX-4GP"
			(at -0.0762 -6.1214 0)
			(unlocked yes)
			(layer "F.Fab")
			(hide yes)
			(effects
				(font
					(size 1.016 1.016)
					(thickness 0.1524)
				)
			)
		)
		(property "Device Type" "C805H58"
			(at -0.0762 -8.1534 0)
			(unlocked yes)
			(layer "F.Fab")
			(hide yes)
			(effects
				(font
					(size 1.016 1.016)
					(thickness 0.1524)
				)
			)
		)
		(duplicate_pad_numbers_are_jumpers no)
		(fp_line
			(start 0.6096 0)
			(end -0.6096 0)
			(stroke
				(width 0.3048)
				(type default)
			)
			(layer "F.SilkS")
		)
		(fp_poly
			(pts
				(xy -0.9017 1.4351) (xy 0.9017 1.4351) (xy 0.9017 -1.4351) (xy -0.9017 -1.4351)
			)
			(stroke
				(width 0)
				(type default)
			)
			(fill no)
			(layer "F.CrtYd")
		)
		(fp_poly
			(pts
				(xy 0.9017 1.4351) (xy 0.9017 -1.4351) (xy -0.9017 -1.4351) (xy -0.9017 1.4351)
			)
			(stroke
				(width 0)
				(type default)
			)
			(fill no)
			(layer "F.Fab")
		)
		(pad "1" smd rect
			(at 0 -0.8382)
			(size 1.5494 0.9398)
			(layers "F.Cu" "F.Mask" "F.Paste")
			(net "TPS74801_1V35_OUT")
		)
		(pad "2" smd rect
			(at 0 0.8382)
			(size 1.5494 0.9398)
			(layers "F.Cu" "F.Mask" "F.Paste")
			(net "GND")
		)
	)
	(footprint ""
		(layer "F.Cu")
		(at 40.767 -50.419 180)
		(property "Reference" "R132"
			(at 0 0 180)
			(layer "F.SilkS")
			(hide yes)
			(effects
				(font
					(size 1.27 1.27)
				)
			)
		)
		(property "Value" "2D2R3J-2-GP"
			(at -0.0254 -2.0193 180)
			(unlocked yes)
			(layer "F.Fab")
			(hide yes)
			(effects
				(font
					(size 1.016 1.016)
					(thickness 0.1524)
				)
			)
		)
		(property "Device Type" "R603H22"
			(at -0.0254 -3.5433 180)
			(unlocked yes)
			(layer "F.Fab")
			(hide yes)
			(effects
				(font
					(size 1.016 1.016)
					(thickness 0.1524)
				)
			)
		)
		(duplicate_pad_numbers_are_jumpers no)
		(fp_line
			(start 0.4318 0)
			(end 0.2032 0)
			(stroke
				(width 0.2032)
				(type default)
			)
			(layer "F.SilkS")
		)
		(fp_line
			(start -0.2032 0)
			(end -0.4191 0)
			(stroke
				(width 0.2032)
				(type default)
			)
			(layer "F.SilkS")
		)
		(fp_rect
			(start -0.635 1.1811)
			(end 0.635 -1.1811)
			(stroke
				(width 0)
				(type default)
			)
			(fill no)
			(layer "F.CrtYd")
		)
		(fp_rect
			(start -0.635 1.1811)
			(end 0.635 -1.1811)
			(stroke
				(width 0)
				(type default)
			)
			(fill no)
			(layer "F.Fab")
		)
		(pad "1" smd custom
			(at 0 -0.6604 180)
			(size 0.19685 0.19685)
			(layers "F.Cu" "F.Mask" "F.Paste")
			(net "P3V3_CLK_R_PCI")
			(options
				(clearance outline)
				(anchor circle)
			)
			(primitives
				(gr_poly
					(pts
						(arc
							(start 0.508 -0.2921)
							(mid 0.478242 -0.363942)
							(end 0.4064 -0.3937)
						)
						(arc
							(start -0.4064 -0.3937)
							(mid -0.478242 -0.363942)
							(end -0.508 -0.2921)
						)
						(arc
							(start -0.508 0.2921)
							(mid -0.478242 0.363942)
							(end -0.4064 0.3937)
						)
						(arc
							(start 0.4064 0.3937)
							(mid 0.478242 0.363942)
							(end 0.508 0.2921)
						)
					)
					(width 0)
					(fill yes)
				)
			)
		)
		(pad "2" smd custom
			(at 0 0.6604 180)
			(size 0.19685 0.19685)
			(layers "F.Cu" "F.Mask" "F.Paste")
			(net "P3V3_CLK_PCI")
			(options
				(clearance outline)
				(anchor circle)
			)
			(primitives
				(gr_poly
					(pts
						(arc
							(start 0.508 -0.2921)
							(mid 0.478242 -0.363942)
							(end 0.4064 -0.3937)
						)
						(arc
							(start -0.4064 -0.3937)
							(mid -0.478242 -0.363942)
							(end -0.508 -0.2921)
						)
						(arc
							(start -0.508 0.2921)
							(mid -0.478242 0.363942)
							(end -0.4064 0.3937)
						)
						(arc
							(start 0.4064 0.3937)
							(mid 0.478242 0.363942)
							(end 0.508 0.2921)
						)
					)
					(width 0)
					(fill yes)
				)
			)
		)
	)
	(footprint ""
		(layer "F.Cu")
		(at 49.657 -18.415 90)
		(property "Reference" "R326"
			(at 0 0 90)
			(layer "F.SilkS")
			(hide yes)
			(effects
				(font
					(size 1.27 1.27)
				)
			)
		)
		(property "Value" "4K7R2F-GP"
			(at 0.064008 -3.993896 90)
			(unlocked yes)
			(layer "F.Fab")
			(hide yes)
			(effects
				(font
					(size 1.016 1.016)
					(thickness 0.1524)
				)
			)
		)
		(property "Device Type" "R402H16"
			(at 0.064008 -5.517896 90)
			(unlocked yes)
			(layer "F.Fab")
			(hide yes)
			(effects
				(font
					(size 1.016 1.016)
					(thickness 0.1524)
				)
			)
		)
		(duplicate_pad_numbers_are_jumpers no)
		(fp_rect
			(start -0.381 0.8382)
			(end 0.381 -0.8382)
			(stroke
				(width 0)
				(type default)
			)
			(fill no)
			(layer "F.CrtYd")
		)
		(fp_rect
			(start -0.381 0.8382)
			(end 0.381 -0.8382)
			(stroke
				(width 0)
				(type default)
			)
			(fill no)
			(layer "F.Fab")
		)
		(pad "1" smd custom
			(at 0 -0.4318 90)
			(size 0.127 0.127)
			(layers "F.Cu" "F.Mask" "F.Paste")
			(net "CLKBUFF_OE0#")
			(options
				(clearance outline)
				(anchor circle)
			)
			(primitives
				(gr_poly
					(pts
						(arc
							(start -0.2032 -0.2794)
							(mid -0.239121 -0.264521)
							(end -0.254 -0.2286)
						)
						(arc
							(start -0.254 0.2286)
							(mid -0.239121 0.264521)
							(end -0.2032 0.2794)
						)
						(arc
							(start 0.2032 0.2794)
							(mid 0.239121 0.264521)
							(end 0.254 0.2286)
						)
						(arc
							(start 0.254 -0.2286)
							(mid 0.239121 -0.264521)
							(end 0.2032 -0.2794)
						)
					)
					(width 0)
					(fill yes)
				)
			)
		)
		(pad "2" smd custom
			(at 0 0.4318 90)
			(size 0.127 0.127)
			(layers "F.Cu" "F.Mask" "F.Paste")
			(net "GND")
			(options
				(clearance outline)
				(anchor circle)
			)
			(primitives
				(gr_poly
					(pts
						(arc
							(start -0.2032 -0.2794)
							(mid -0.239121 -0.264521)
							(end -0.254 -0.2286)
						)
						(arc
							(start -0.254 0.2286)
							(mid -0.239121 0.264521)
							(end -0.2032 0.2794)
						)
						(arc
							(start 0.2032 0.2794)
							(mid 0.239121 0.264521)
							(end 0.254 0.2286)
						)
						(arc
							(start 0.254 -0.2286)
							(mid 0.239121 -0.264521)
							(end 0.2032 -0.2794)
						)
					)
					(width 0)
					(fill yes)
				)
			)
		)
	)
	(footprint ""
		(layer "F.Cu")
		(at 73.533 -55.118 180)
		(property "Reference" "R134"
			(at 0 0 180)
			(layer "F.SilkS")
			(hide yes)
			(effects
				(font
					(size 1.27 1.27)
				)
			)
		)
		(property "Value" "0R2J-2-GP"
			(at 0.064008 -3.993896 180)
			(unlocked yes)
			(layer "F.Fab")
			(hide yes)
			(effects
				(font
					(size 1.016 1.016)
					(thickness 0.1524)
				)
			)
		)
		(property "Device Type" "R402H16"
			(at 0.064008 -5.517896 180)
			(unlocked yes)
			(layer "F.Fab")
			(hide yes)
			(effects
				(font
					(size 1.016 1.016)
					(thickness 0.1524)
				)
			)
		)
		(duplicate_pad_numbers_are_jumpers no)
		(fp_rect
			(start -0.381 0.8382)
			(end 0.381 -0.8382)
			(stroke
				(width 0)
				(type default)
			)
			(fill no)
			(layer "F.CrtYd")
		)
		(fp_rect
			(start -0.381 0.8382)
			(end 0.381 -0.8382)
			(stroke
				(width 0)
				(type default)
			)
			(fill no)
			(layer "F.Fab")
		)
		(pad "1" smd custom
			(at 0 -0.4318 180)
			(size 0.127 0.127)
			(layers "F.Cu" "F.Mask" "F.Paste")
			(net "P1V0")
			(options
				(clearance outline)
				(anchor circle)
			)
			(primitives
				(gr_poly
					(pts
						(arc
							(start -0.2032 -0.2794)
							(mid -0.239121 -0.264521)
							(end -0.254 -0.2286)
						)
						(arc
							(start -0.254 0.2286)
							(mid -0.239121 0.264521)
							(end -0.2032 0.2794)
						)
						(arc
							(start 0.2032 0.2794)
							(mid 0.239121 0.264521)
							(end 0.254 0.2286)
						)
						(arc
							(start 0.254 -0.2286)
							(mid 0.239121 -0.264521)
							(end 0.2032 -0.2794)
						)
					)
					(width 0)
					(fill yes)
				)
			)
		)
		(pad "2" smd custom
			(at 0 0.4318 180)
			(size 0.127 0.127)
			(layers "F.Cu" "F.Mask" "F.Paste")
			(net "P1V0_SENSE")
			(options
				(clearance outline)
				(anchor circle)
			)
			(primitives
				(gr_poly
					(pts
						(arc
							(start -0.2032 -0.2794)
							(mid -0.239121 -0.264521)
							(end -0.254 -0.2286)
						)
						(arc
							(start -0.254 0.2286)
							(mid -0.239121 0.264521)
							(end -0.2032 0.2794)
						)
						(arc
							(start 0.2032 0.2794)
							(mid 0.239121 0.264521)
							(end 0.254 0.2286)
						)
						(arc
							(start 0.254 -0.2286)
							(mid 0.239121 -0.264521)
							(end 0.2032 -0.2794)
						)
					)
					(width 0)
					(fill yes)
				)
			)
		)
	)
	(footprint ""
		(layer "F.Cu")
		(at 47.8536 -52.0065)
		(property "Reference" "C35"
			(at 0 0 0)
			(layer "F.SilkS")
			(hide yes)
			(effects
				(font
					(size 1.27 1.27)
				)
			)
		)
		(property "Value" "SCD1U10V2KX-5GP"
			(at 1.8923 -1.2065 0)
			(unlocked yes)
			(layer "F.Fab")
			(hide yes)
			(effects
				(font
					(size 1.016 1.016)
					(thickness 0.1524)
				)
			)
		)
		(property "Device Type" "C402H22"
			(at 1.8923 -2.7305 0)
			(unlocked yes)
			(layer "F.Fab")
			(hide yes)
			(effects
				(font
					(size 1.016 1.016)
					(thickness 0.1524)
				)
			)
		)
		(duplicate_pad_numbers_are_jumpers no)
		(fp_rect
			(start -0.381 0.7366)
			(end 0.381 -0.7366)
			(stroke
				(width 0)
				(type default)
			)
			(fill no)
			(layer "F.CrtYd")
		)
		(fp_rect
			(start -0.381 0.7366)
			(end 0.381 -0.7366)
			(stroke
				(width 0)
				(type default)
			)
			(fill no)
			(layer "F.Fab")
		)
		(pad "1" smd custom
			(at 0 -0.4572)
			(size 0.1143 0.1143)
			(layers "F.Cu" "F.Mask" "F.Paste")
			(net "P1V5_CLK_VDD_CORE")
			(options
				(clearance outline)
				(anchor circle)
			)
			(primitives
				(gr_poly
					(pts
						(arc
							(start -0.254 -0.1778)
							(mid -0.239121 -0.213721)
							(end -0.2032 -0.2286)
						)
						(arc
							(start 0.2032 -0.2286)
							(mid 0.239121 -0.213721)
							(end 0.254 -0.1778)
						)
						(arc
							(start 0.254 0.1778)
							(mid 0.239121 0.213721)
							(end 0.2032 0.2286)
						)
						(arc
							(start -0.2032 0.2286)
							(mid -0.239121 0.213721)
							(end -0.254 0.1778)
						)
					)
					(width 0)
					(fill yes)
				)
			)
		)
		(pad "2" smd custom
			(at 0 0.4572)
			(size 0.1143 0.1143)
			(layers "F.Cu" "F.Mask" "F.Paste")
			(net "GND")
			(options
				(clearance outline)
				(anchor circle)
			)
			(primitives
				(gr_poly
					(pts
						(arc
							(start -0.254 -0.1778)
							(mid -0.239121 -0.213721)
							(end -0.2032 -0.2286)
						)
						(arc
							(start 0.2032 -0.2286)
							(mid 0.239121 -0.213721)
							(end 0.254 -0.1778)
						)
						(arc
							(start 0.254 0.1778)
							(mid 0.239121 0.213721)
							(end 0.2032 0.2286)
						)
						(arc
							(start -0.2032 0.2286)
							(mid -0.239121 0.213721)
							(end -0.254 0.1778)
						)
					)
					(width 0)
					(fill yes)
				)
			)
		)
	)
	(footprint ""
		(layer "F.Cu")
		(at 74.041 -33.655 90)
		(property "Reference" "R107"
			(at 0 0 90)
			(layer "F.SilkS")
			(hide yes)
			(effects
				(font
					(size 1.27 1.27)
				)
			)
		)
		(property "Value" "4K7R2F-GP"
			(at 0.064008 -3.993896 90)
			(unlocked yes)
			(layer "F.Fab")
			(hide yes)
			(effects
				(font
					(size 1.016 1.016)
					(thickness 0.1524)
				)
			)
		)
		(property "Device Type" "R402H16"
			(at 0.064008 -5.517896 90)
			(unlocked yes)
			(layer "F.Fab")
			(hide yes)
			(effects
				(font
					(size 1.016 1.016)
					(thickness 0.1524)
				)
			)
		)
		(duplicate_pad_numbers_are_jumpers no)
		(fp_rect
			(start -0.381 0.8382)
			(end 0.381 -0.8382)
			(stroke
				(width 0)
				(type default)
			)
			(fill no)
			(layer "F.CrtYd")
		)
		(fp_rect
			(start -0.381 0.8382)
			(end 0.381 -0.8382)
			(stroke
				(width 0)
				(type default)
			)
			(fill no)
			(layer "F.Fab")
		)
		(pad "1" smd custom
			(at 0 -0.4318 90)
			(size 0.127 0.127)
			(layers "F.Cu" "F.Mask" "F.Paste")
			(net "P3V3_CPU")
			(options
				(clearance outline)
				(anchor circle)
			)
			(primitives
				(gr_poly
					(pts
						(arc
							(start -0.2032 -0.2794)
							(mid -0.239121 -0.264521)
							(end -0.254 -0.2286)
						)
						(arc
							(start -0.254 0.2286)
							(mid -0.239121 0.264521)
							(end -0.2032 0.2794)
						)
						(arc
							(start 0.2032 0.2794)
							(mid 0.239121 0.264521)
							(end 0.254 0.2286)
						)
						(arc
							(start 0.254 -0.2286)
							(mid 0.239121 -0.264521)
							(end 0.2032 -0.2794)
						)
					)
					(width 0)
					(fill yes)
				)
			)
		)
		(pad "2" smd custom
			(at 0 0.4318 90)
			(size 0.127 0.127)
			(layers "F.Cu" "F.Mask" "F.Paste")
			(net "XDP_CPU_RESET#")
			(options
				(clearance outline)
				(anchor circle)
			)
			(primitives
				(gr_poly
					(pts
						(arc
							(start -0.2032 -0.2794)
							(mid -0.239121 -0.264521)
							(end -0.254 -0.2286)
						)
						(arc
							(start -0.254 0.2286)
							(mid -0.239121 0.264521)
							(end -0.2032 0.2794)
						)
						(arc
							(start 0.2032 0.2794)
							(mid 0.239121 0.264521)
							(end 0.254 0.2286)
						)
						(arc
							(start 0.254 -0.2286)
							(mid 0.239121 -0.264521)
							(end 0.2032 -0.2794)
						)
					)
					(width 0)
					(fill yes)
				)
			)
		)
	)
)
